# T6G (Grand Teton) — schematic netlist excerpt (pin names and nets, part order shuffled) for the footprints in the layout excerpt that follows; sources: Cadence DE-HDL packaged netlist, KiCad conversion of 04192023_DAF0TMB3IC0_F0TG_MB_C_brd_V02_OCP.brd

R1162  Q_RES  0 5% CHIP  pkg 0402LF  page 161 : A = SMB_CPU1_SEC_R_SDA ; B = SMB_CPU1_SEC_SDA
C655  Q_CAP  1UF 4V 20% X6S  pkg 0201  page 290 : A = P0V9_CPU0_RT_2D ; B = GND
R920  Q_RES  4.7K 5% EMPTY  pkg 0201LF  page 353 : A = P1V8_CPU1_RT_1D ; B = TEST1_RT_CPU1_P3

(kicad_pcb
	(version 20260206)
	(generator "pcbnew")
	(generator_version "10.0")
	(general
		(thickness 1.6)
		(legacy_teardrops no)
	)
	(paper "A4")
	(title_block
		(title "04192023_DAF0TMB3IC0_F0TG_MB_C_brd_V02_OCP.brd")
		(comment 1 "Grand Teton / footprints 7337-7339 of 8354")
	)
	(layers
		(0 "F.Cu" signal "TOP")
		(4 "In1.Cu" signal "GND")
		(6 "In2.Cu" signal "IN1")
		(8 "In3.Cu" signal "GND1")
		(10 "In4.Cu" signal "IN2")
		(12 "In5.Cu" signal "GND2")
		(14 "In6.Cu" signal "IN3")
		(16 "In7.Cu" signal "GND3")
		(18 "In8.Cu" signal "VCC")
		(20 "In9.Cu" signal "VCC1")
		(22 "In10.Cu" signal "GND4")
		(24 "In11.Cu" signal "IN4")
		(26 "In12.Cu" signal "GND5")
		(28 "In13.Cu" signal "IN5")
		(30 "In14.Cu" signal "GND6")
		(32 "In15.Cu" signal "IN6")
		(34 "In16.Cu" signal "GND7")
		(2 "B.Cu" signal "BOTTOM")
		(9 "F.Adhes" user "F.Adhesive")
		(11 "B.Adhes" user "B.Adhesive")
		(13 "F.Paste" user "Package Geometry/Pastemask Top")
		(15 "B.Paste" user "Package Geometry/Pastemask Bottom")
		(5 "F.SilkS" user "Ref Des/Silkscreen Top")
		(7 "B.SilkS" user "Ref Des/Silkscreen Bottom")
		(1 "F.Mask" user "Board Geometry/Soldermask Top")
		(3 "B.Mask" user "Board Geometry/Soldermask Bottom")
		(17 "Dwgs.User" user "User.Drawings")
		(19 "Cmts.User" user "User.Comments")
		(21 "Eco1.User" user "User.Eco1")
		(23 "Eco2.User" user "User.Eco2")
		(25 "Edge.Cuts" user "Board Geometry/Outline")
		(27 "Margin" user)
		(31 "F.CrtYd" user "Package Geometry/Place Bound Top")
		(29 "B.CrtYd" user "Package Geometry/Place Bound Bottom")
		(35 "F.Fab" user "Ref Des/Assembly Top")
		(33 "B.Fab" user "Ref Des/Assembly Bottom")
	)
	(footprint ""
		(layer "B.Cu")
		(at 109.095794 -384.66268 180)
		(property "Reference" "R920"
			(at 0 0 0)
			(layer "B.SilkS")
			(hide yes)
			(effects
				(font
					(size 1.27 1.27)
				)
				(justify mirror)
			)
		)
		(property "Value" ""
			(at 0 0 0)
			(layer "B.Fab")
			(effects
				(font
					(size 1.27 1.27)
				)
				(justify mirror)
			)
		)
		(duplicate_pad_numbers_are_jumpers no)
		(fp_line
			(start 0.32512 0.175006)
			(end 0.32512 -0.175006)
			(stroke
				(width 0.1)
				(type default)
			)
			(layer "B.Fab")
		)
		(fp_line
			(start 0.32512 -0.175006)
			(end -0.32512 -0.175006)
			(stroke
				(width 0.1)
				(type default)
			)
			(layer "B.Fab")
		)
		(fp_line
			(start -0.32512 0.175006)
			(end 0.32512 0.175006)
			(stroke
				(width 0.1)
				(type default)
			)
			(layer "B.Fab")
		)
		(fp_line
			(start -0.32512 -0.175006)
			(end -0.32512 0.175006)
			(stroke
				(width 0.1)
				(type default)
			)
			(layer "B.Fab")
		)
		(pad "1" smd rect
			(at 0.2667 0)
			(size 0.3048 0.381)
			(layers "B.Cu" "B.Mask" "B.Paste")
			(net "P1V8_CPU1_RT_1D")
		)
		(pad "2" smd rect
			(at -0.2667 0 180)
			(size 0.3048 0.381)
			(layers "B.Cu" "B.Mask" "B.Paste")
			(net "TEST1_RT_CPU1_P3")
		)
	)
	(footprint ""
		(layer "B.Cu")
		(at 235.077 -234.061 90)
		(property "Reference" "R1162"
			(at 0 0 90)
			(layer "B.SilkS")
			(hide yes)
			(effects
				(font
					(size 1.27 1.27)
				)
				(justify mirror)
			)
		)
		(property "Value" ""
			(at 0 0 90)
			(layer "B.Fab")
			(effects
				(font
					(size 1.27 1.27)
				)
				(justify mirror)
			)
		)
		(duplicate_pad_numbers_are_jumpers no)
		(fp_line
			(start 0.7874 -0.4064)
			(end -0.7874 -0.4064)
			(stroke
				(width 0.1524)
				(type default)
			)
			(layer "B.SilkS")
		)
		(fp_line
			(start -0.7874 -0.4064)
			(end -0.7874 0.4064)
			(stroke
				(width 0.1524)
				(type default)
			)
			(layer "B.SilkS")
		)
		(fp_line
			(start 0.7874 0.4064)
			(end 0.7874 -0.4064)
			(stroke
				(width 0.1524)
				(type default)
			)
			(layer "B.SilkS")
		)
		(fp_line
			(start -0.7874 0.4064)
			(end 0.7874 0.4064)
			(stroke
				(width 0.1524)
				(type default)
			)
			(layer "B.SilkS")
		)
		(fp_line
			(start 0.67945 -0.305054)
			(end 0.12065 -0.305054)
			(stroke
				(width 0.1)
				(type default)
			)
			(layer "B.Fab")
		)
		(fp_line
			(start 0.12065 -0.305054)
			(end 0.12065 -0.2794)
			(stroke
				(width 0.1)
				(type default)
			)
			(layer "B.Fab")
		)
		(fp_line
			(start -0.12065 -0.3048)
			(end -0.67945 -0.3048)
			(stroke
				(width 0.1)
				(type default)
			)
			(layer "B.Fab")
		)
		(fp_line
			(start -0.67945 -0.3048)
			(end -0.67945 0.3048)
			(stroke
				(width 0.1)
				(type default)
			)
			(layer "B.Fab")
		)
		(fp_line
			(start 0.12065 -0.2794)
			(end -0.12065 -0.2794)
			(stroke
				(width 0.1)
				(type default)
			)
			(layer "B.Fab")
		)
		(fp_line
			(start -0.12065 -0.2794)
			(end -0.12065 -0.3048)
			(stroke
				(width 0.1)
				(type default)
			)
			(layer "B.Fab")
		)
		(fp_line
			(start 0.12065 0.2794)
			(end 0.12065 0.3048)
			(stroke
				(width 0.1)
				(type default)
			)
			(layer "B.Fab")
		)
		(fp_line
			(start -0.120396 0.2794)
			(end 0.12065 0.2794)
			(stroke
				(width 0.1)
				(type default)
			)
			(layer "B.Fab")
		)
		(fp_line
			(start 0.67945 0.3048)
			(end 0.67945 -0.305054)
			(stroke
				(width 0.1)
				(type default)
			)
			(layer "B.Fab")
		)
		(fp_line
			(start 0.12065 0.3048)
			(end 0.67945 0.3048)
			(stroke
				(width 0.1)
				(type default)
			)
			(layer "B.Fab")
		)
		(fp_line
			(start -0.120396 0.3048)
			(end -0.120396 0.2794)
			(stroke
				(width 0.1)
				(type default)
			)
			(layer "B.Fab")
		)
		(fp_line
			(start -0.67945 0.3048)
			(end -0.120396 0.3048)
			(stroke
				(width 0.1)
				(type default)
			)
			(layer "B.Fab")
		)
		(pad "1" smd circle
			(at 0.40005 0 270)
			(size 0 0)
			(layers "B.Cu" "B.Mask" "B.Paste")
			(net "SMB_CPU1_SEC_R_SDA")
		)
		(pad "2" smd circle
			(at -0.40005 0 270)
			(size 0 0)
			(layers "B.Cu" "B.Mask" "B.Paste")
			(net "SMB_CPU1_SEC_SDA")
		)
	)
	(footprint ""
		(layer "B.Cu")
		(at 347.918786 -399.291302 90)
		(property "Reference" "C655"
			(at 0 0 90)
			(layer "B.SilkS")
			(hide yes)
			(effects
				(font
					(size 1.27 1.27)
				)
				(justify mirror)
			)
		)
		(property "Value" ""
			(at 0 0 90)
			(layer "B.Fab")
			(effects
				(font
					(size 1.27 1.27)
				)
				(justify mirror)
			)
		)
		(duplicate_pad_numbers_are_jumpers no)
		(fp_line
			(start 0.299974 -0.150114)
			(end -0.299974 -0.150114)
			(stroke
				(width 0.1)
				(type default)
			)
			(layer "B.Fab")
		)
		(fp_line
			(start -0.299974 -0.150114)
			(end -0.299974 0.150114)
			(stroke
				(width 0.1)
				(type default)
			)
			(layer "B.Fab")
		)
		(fp_line
			(start 0.299974 0.150114)
			(end 0.299974 -0.150114)
			(stroke
				(width 0.1)
				(type default)
			)
			(layer "B.Fab")
		)
		(fp_line
			(start -0.299974 0.150114)
			(end 0.299974 0.150114)
			(stroke
				(width 0.1)
				(type default)
			)
			(layer "B.Fab")
		)
		(pad "1" smd rect
			(at 0.2667 0 270)
			(size 0.3048 0.381)
			(layers "B.Cu" "B.Mask" "B.Paste")
			(net "P0V9_CPU0_RT_2D")
		)
		(pad "2" smd rect
			(at -0.2667 0 270)
			(size 0.3048 0.381)
			(layers "B.Cu" "B.Mask" "B.Paste")
			(net "GND")
		)
	)
)
